# BASEBOARD_FAB2 (Tioga Pass) — schematic netlist excerpt (pin names and nets, part order shuffled) for the footprints in the layout excerpt that follows; sources: Cadence DE-HDL packaged netlist, KiCad conversion of Wiwynn_Tioga_Pass_MB.brd

R9W32  RES  10.0K 1% CHIP  pkg 0402  page 239 : A = VR_P2V5_BMC_STBY_FB ; B = GND
C1L9  CAP_A  0.1UF 16V 10% X7R  pkg 0402V  page 175 : A = P3V3_STBY ; B = GND
R12W2  665KR5B-1-GP  0.1%  pkg SMD-RG3  page 197 : \1\ = P12V_NVDIMM_ABC_D ; \2\ = VR_PVDDQ_ABC_VINSEN

(kicad_pcb
	(version 20260206)
	(generator "pcbnew")
	(generator_version "10.0")
	(general
		(thickness 1.6)
		(legacy_teardrops no)
	)
	(paper "A4")
	(title_block
		(title "Wiwynn_Tioga_Pass_MB.brd")
		(comment 1 "Tioga Pass / footprints 2270-2272 of 4770")
	)
	(layers
		(0 "F.Cu" signal "TOP")
		(4 "In1.Cu" signal "L2GND")
		(6 "In2.Cu" signal "L3")
		(8 "In3.Cu" signal "L4GND")
		(10 "In4.Cu" signal "L5")
		(12 "In5.Cu" signal "L6GND")
		(14 "In6.Cu" signal "L7VCC")
		(16 "In7.Cu" signal "L8VCC")
		(18 "In8.Cu" signal "L9GND")
		(20 "In9.Cu" signal "L10")
		(22 "In10.Cu" signal "L11GND")
		(24 "In11.Cu" signal "L12")
		(26 "In12.Cu" signal "L13GND")
		(2 "B.Cu" signal "BOTTOM")
		(9 "F.Adhes" user "F.Adhesive")
		(11 "B.Adhes" user "B.Adhesive")
		(13 "F.Paste" user "Package Geometry/Pastemask Top")
		(15 "B.Paste" user "Package Geometry/Pastemask Bottom")
		(5 "F.SilkS" user "Ref Des/Silkscreen Top")
		(7 "B.SilkS" user "Ref Des/Silkscreen Bottom")
		(1 "F.Mask" user "Board Geometry/Soldermask Top")
		(3 "B.Mask" user "Board Geometry/Soldermask Bottom")
		(17 "Dwgs.User" user "User.Drawings")
		(19 "Cmts.User" user "User.Comments")
		(21 "Eco1.User" user "User.Eco1")
		(23 "Eco2.User" user "User.Eco2")
		(25 "Edge.Cuts" user "Board Geometry/Outline")
		(27 "Margin" user)
		(31 "F.CrtYd" user "Package Geometry/Place Bound Top")
		(29 "B.CrtYd" user "Package Geometry/Place Bound Bottom")
		(35 "F.Fab" user "Ref Des/Assembly Top")
		(33 "B.Fab" user "Ref Des/Assembly Bottom")
	)
	(footprint ""
		(layer "F.Cu")
		(at 476.4659 -147.4089 -90)
		(property "Reference" "C1L9"
			(at 0 0 270)
			(layer "F.SilkS")
			(hide yes)
			(effects
				(font
					(size 1.27 1.27)
				)
			)
		)
		(property "Value" ""
			(at 0 0 270)
			(layer "F.Fab")
			(effects
				(font
					(size 1.27 1.27)
				)
			)
		)
		(duplicate_pad_numbers_are_jumpers no)
		(fp_poly
			(pts
				(xy 0.3048 -0.1016) (xy 0.3048 0.9906) (xy -0.3048 0.9906) (xy -0.3048 -0.1016)
			)
			(stroke
				(width 0)
				(type default)
			)
			(fill no)
			(layer "F.CrtYd")
		)
		(fp_line
			(start -0.3048 0.9906)
			(end 0.3048 0.9906)
			(stroke
				(width 0.1)
				(type default)
			)
			(layer "F.Fab")
		)
		(fp_line
			(start 0.3048 0.9906)
			(end 0.3048 -0.1016)
			(stroke
				(width 0.1)
				(type default)
			)
			(layer "F.Fab")
		)
		(fp_line
			(start -0.3048 -0.1016)
			(end -0.3048 0.9906)
			(stroke
				(width 0.1)
				(type default)
			)
			(layer "F.Fab")
		)
		(fp_line
			(start 0.3048 -0.1016)
			(end -0.3048 -0.1016)
			(stroke
				(width 0.1)
				(type default)
			)
			(layer "F.Fab")
		)
		(pad "1" smd rect
			(at 0 0 270)
			(size 0.508 0.508)
			(layers "F.Cu" "F.Mask" "F.Paste")
			(net "P3V3_STBY")
		)
		(pad "2" smd rect
			(at 0 0.889 270)
			(size 0.508 0.508)
			(layers "F.Cu" "F.Mask" "F.Paste")
			(net "GND")
		)
		(zone
			(layer "F.Cu")
			(hatch none 0.5)
			(connect_pads
				(clearance 0)
			)
			(min_thickness 0.25)
			(keepout
				(tracks not_allowed)
				(vias allowed)
				(pads allowed)
				(copperpour not_allowed)
				(footprints allowed)
			)
			(placement
				(enabled no)
				(sheetname "")
			)
			(fill
				(thermal_gap 0.5)
				(thermal_bridge_width 0.5)
				(island_removal_mode 0)
			)
			(polygon
				(pts
					(xy 475.8309 -147.6629) (xy 475.8309 -147.1549) (xy 476.2119 -147.1549) (xy 476.2119 -147.6629)
				)
			)
		)
		(zone
			(layer "F.Cu")
			(hatch none 0.5)
			(connect_pads
				(clearance 0)
			)
			(min_thickness 0.25)
			(keepout
				(tracks allowed)
				(vias not_allowed)
				(pads allowed)
				(copperpour not_allowed)
				(footprints allowed)
			)
			(placement
				(enabled no)
				(sheetname "")
			)
			(fill
				(thermal_gap 0.5)
				(thermal_bridge_width 0.5)
				(island_removal_mode 0)
			)
			(polygon
				(pts
					(xy 476.2119 -147.6629) (xy 476.2119 -147.1549) (xy 475.8309 -147.1549) (xy 475.8309 -147.6629)
				)
			)
		)
	)
	(footprint ""
		(layer "F.Cu")
		(at 351.731834 -21.284438)
		(property "Reference" "R12W2"
			(at 0 0 0)
			(layer "F.SilkS")
			(hide yes)
			(effects
				(font
					(size 1.27 1.27)
				)
			)
		)
		(property "Value" "*"
			(at 0 -8.9535 0)
			(unlocked yes)
			(layer "F.Fab")
			(hide yes)
			(effects
				(font
					(size 1.27 1.016)
					(thickness 0.1524)
				)
			)
		)
		(property "Device Type" "665KR5B-1-GP_SMD-RG3-665KR5B-1A"
			(at 0 -10.6299 0)
			(unlocked yes)
			(layer "F.Fab")
			(hide yes)
			(effects
				(font
					(size 1.27 1.016)
					(thickness 0.1524)
				)
			)
		)
		(duplicate_pad_numbers_are_jumpers no)
		(fp_line
			(start -0.889 -1.7018)
			(end -0.889 0.2794)
			(stroke
				(width 0.1524)
				(type default)
			)
			(layer "F.SilkS")
		)
		(fp_line
			(start -0.889 0.0762)
			(end -0.889 1.7018)
			(stroke
				(width 0.1524)
				(type default)
			)
			(layer "F.SilkS")
		)
		(fp_line
			(start -0.889 1.7018)
			(end 0.889 1.7018)
			(stroke
				(width 0.1524)
				(type default)
			)
			(layer "F.SilkS")
		)
		(fp_line
			(start 0.889 -1.7018)
			(end -0.889 -1.7018)
			(stroke
				(width 0.1524)
				(type default)
			)
			(layer "F.SilkS")
		)
		(fp_line
			(start 0.889 -1.7018)
			(end 0.889 -0.381)
			(stroke
				(width 0.1524)
				(type default)
			)
			(layer "F.SilkS")
		)
		(fp_line
			(start 0.889 1.7018)
			(end 0.889 -0.508)
			(stroke
				(width 0.1524)
				(type default)
			)
			(layer "F.SilkS")
		)
		(fp_poly
			(pts
				(xy 0.9652 -1.778) (xy 0.9652 1.778) (xy -0.9652 1.778) (xy -0.9652 -1.778)
			)
			(stroke
				(width 0)
				(type default)
			)
			(fill no)
			(layer "F.CrtYd")
		)
		(fp_rect
			(start -0.9652 1.778)
			(end 0.9652 -1.778)
			(stroke
				(width 0)
				(type default)
			)
			(fill no)
			(layer "F.Fab")
		)
		(pad "1" smd rect
			(at 0 -0.9652)
			(size 1.397 1.143)
			(layers "F.Cu" "F.Mask" "F.Paste")
			(net "P12V_NVDIMM_ABC_D")
		)
		(pad "2" smd rect
			(at 0 0.9652)
			(size 1.397 1.143)
			(layers "F.Cu" "F.Mask" "F.Paste")
			(net "VR_PVDDQ_ABC_VINSEN")
		)
	)
	(footprint ""
		(layer "F.Cu")
		(at 450.215 -21.209 -90)
		(property "Reference" "R9W32"
			(at -0.8382 -0.67818 270)
			(unlocked yes)
			(layer "F.SilkS")
			(effects
				(font
					(size 0.4064 0.254)
					(thickness 0.1524)
				)
				(justify left)
			)
		)
		(property "Value" ""
			(at 0 0 270)
			(layer "F.Fab")
			(effects
				(font
					(size 1.27 1.27)
				)
			)
		)
		(duplicate_pad_numbers_are_jumpers no)
		(fp_poly
			(pts
				(xy -0.2794 -0.1016) (xy 0.2794 -0.1016) (xy 0.2794 0.9906) (xy -0.2794 0.9906)
			)
			(stroke
				(width 0)
				(type default)
			)
			(fill no)
			(layer "F.CrtYd")
		)
		(fp_line
			(start -0.2794 0.9906)
			(end 0.2794 0.9906)
			(stroke
				(width 0.1)
				(type default)
			)
			(layer "F.Fab")
		)
		(fp_line
			(start 0.2794 0.9906)
			(end 0.2794 -0.1016)
			(stroke
				(width 0.1)
				(type default)
			)
			(layer "F.Fab")
		)
		(fp_line
			(start -0.2794 -0.1016)
			(end -0.2794 0.9906)
			(stroke
				(width 0.1)
				(type default)
			)
			(layer "F.Fab")
		)
		(fp_line
			(start 0.2794 -0.1016)
			(end -0.2794 -0.1016)
			(stroke
				(width 0.1)
				(type default)
			)
			(layer "F.Fab")
		)
		(pad "1" smd rect
			(at 0 0 270)
			(size 0.508 0.508)
			(layers "F.Cu" "F.Mask" "F.Paste")
			(net "VR_P2V5_BMC_STBY_FB")
		)
		(pad "2" smd rect
			(at 0 0.889 270)
			(size 0.508 0.508)
			(layers "F.Cu" "F.Mask" "F.Paste")
			(net "GND")
		)
		(zone
			(layer "F.Cu")
			(hatch none 0.5)
			(connect_pads
				(clearance 0)
			)
			(min_thickness 0.25)
			(keepout
				(tracks not_allowed)
				(vias allowed)
				(pads allowed)
				(copperpour not_allowed)
				(footprints allowed)
			)
			(placement
				(enabled no)
				(sheetname "")
			)
			(fill
				(thermal_gap 0.5)
				(thermal_bridge_width 0.5)
				(island_removal_mode 0)
			)
			(polygon
				(pts
					(xy 449.58 -21.463) (xy 449.58 -20.955) (xy 449.961 -20.955) (xy 449.961 -21.463)
				)
			)
		)
		(zone
			(layer "F.Cu")
			(hatch none 0.5)
			(connect_pads
				(clearance 0)
			)
			(min_thickness 0.25)
			(keepout
				(tracks allowed)
				(vias not_allowed)
				(pads allowed)
				(copperpour not_allowed)
				(footprints allowed)
			)
			(placement
				(enabled no)
				(sheetname "")
			)
			(fill
				(thermal_gap 0.5)
				(thermal_bridge_width 0.5)
				(island_removal_mode 0)
			)
			(polygon
				(pts
					(xy 449.961 -21.463) (xy 449.961 -20.955) (xy 449.58 -20.955) (xy 449.58 -21.463)
				)
			)
		)
	)
)
